(kicad_pcb
	(version 20241229)
	(generator "pcbnew")
	(generator_version "9.0")
	(general
		(thickness 1.711)
		(legacy_teardrops no)
	)
	(paper "A4")
	(title_block
		(title "Antmicro Baseboard for Jetson AGX Thor")
		(date "2026-02-18")
		(rev "1.1.0")
		(company "Antmicro Ltd")
		(comment 1 "www.antmicro.com")
		(comment 9 "footprints 340-342 of 1170")
	)
	(layers
		(0 "F.Cu" signal)
		(4 "In1.Cu" signal)
		(6 "In2.Cu" signal)
		(8 "In3.Cu" signal)
		(10 "In4.Cu" jumper)
		(12 "In5.Cu" signal)
		(14 "In6.Cu" signal)
		(16 "In7.Cu" signal)
		(18 "In8.Cu" signal)
		(2 "B.Cu" signal)
		(9 "F.Adhes" user "F.Adhesive")
		(11 "B.Adhes" user "B.Adhesive")
		(13 "F.Paste" user)
		(15 "B.Paste" user)
		(5 "F.SilkS" user "F.Silkscreen")
		(7 "B.SilkS" user "B.Silkscreen")
		(1 "F.Mask" user)
		(3 "B.Mask" user)
		(17 "Dwgs.User" user "User.Drawings")
		(19 "Cmts.User" user "User.Comments")
		(21 "Eco1.User" user "User.Eco1")
		(23 "Eco2.User" user "User.Eco2")
		(25 "Edge.Cuts" user)
		(27 "Margin" user)
		(31 "F.CrtYd" user "F.Courtyard")
		(29 "B.CrtYd" user "B.Courtyard")
		(35 "F.Fab" user)
		(33 "B.Fab" user)
	)
	(footprint "antmicro-footprints:LED_0603_1608Metric_G"
		(layer "F.Cu")
		(at 196.17 88.22 90)
		(descr "LED SMD 0603 Green")
		(tags "LED SMD 0603 Green")
		(property "Reference" "D18"
			(at -3.42 0.35 90)
			(layer "F.SilkS")
			(effects
				(font
					(size 0.7 0.7)
					(thickness 0.15)
				)
				(justify left bottom)
			)
		)
		(property "Value" "LED_G_0603_LTST-C190GKT"
			(at -0.001 1.599 90)
			(layer "F.Fab")
			(effects
				(font
					(size 0.7 0.7)
					(thickness 0.15)
				)
				(justify left bottom)
			)
		)
		(property "Datasheet" "https://media.digikey.com/pdf/Data%20Sheets/Lite-On%20PDFs/LTST-C190GKT.pdf"
			(at 0 0 90)
			(layer "F.Fab")
			(hide yes)
			(effects
				(font
					(size 1.27 1.27)
					(thickness 0.15)
				)
			)
		)
		(property "Description" "LED, Green, SMD, 0603, 20 mA, 2.1 V, 569 nm"
			(at 0 0 90)
			(layer "F.Fab")
			(hide yes)
			(effects
				(font
					(size 1.27 1.27)
					(thickness 0.15)
				)
			)
		)
		(property "MPN" "LTST-C190GKT"
			(at 0 0 90)
			(unlocked yes)
			(layer "F.Fab")
			(hide yes)
			(effects
				(font
					(size 1 1)
					(thickness 0.15)
				)
			)
		)
		(property "Manufacturer" "Lite-On"
			(at 0 0 90)
			(unlocked yes)
			(layer "F.Fab")
			(hide yes)
			(effects
				(font
					(size 1 1)
					(thickness 0.15)
				)
			)
		)
		(property "Author" "Antmicro"
			(at 0 0 90)
			(unlocked yes)
			(layer "F.Fab")
			(hide yes)
			(effects
				(font
					(size 1 1)
					(thickness 0.15)
				)
			)
		)
		(property "License" "Apache-2.0"
			(at 0 0 90)
			(unlocked yes)
			(layer "F.Fab")
			(hide yes)
			(effects
				(font
					(size 1 1)
					(thickness 0.15)
				)
			)
		)
		(property "Color" "Green"
			(at 0 0 90)
			(unlocked yes)
			(layer "F.Fab")
			(hide yes)
			(effects
				(font
					(size 1 1)
					(thickness 0.15)
				)
			)
		)
		(sheetname "/USB Debug, PD/")
		(sheetfile "usb_debug_pd.kicad_sch")
		(attr smd)
		(fp_line
			(start 0.22 -0.35)
			(end -0.22 -0.35)
			(stroke
				(width 0.15)
				(type solid)
			)
			(layer "F.SilkS")
		)
		(fp_line
			(start -1.18 -0.319)
			(end -1.18 0.321)
			(stroke
				(width 0.15)
				(type solid)
			)
			(layer "F.SilkS")
		)
		(fp_line
			(start 0.105328 0.001008)
			(end 0.24 0.001)
			(stroke
				(width 0.1)
				(type solid)
			)
			(layer "F.SilkS")
		)
		(fp_line
			(start -0.094672 0.001008)
			(end 0.105328 -0.198992)
			(stroke
				(width 0.1)
				(type solid)
			)
			(layer "F.SilkS")
		)
		(fp_line
			(start -0.094672 0.001008)
			(end -0.24 0.001008)
			(stroke
				(width 0.1)
				(type solid)
			)
			(layer "F.SilkS")
		)
		(fp_line
			(start 0.105328 0.201008)
			(end 0.105328 -0.198992)
			(stroke
				(width 0.1)
				(type solid)
			)
			(layer "F.SilkS")
		)
		(fp_line
			(start 0.105328 0.201008)
			(end -0.094672 0.001008)
			(stroke
				(width 0.1)
				(type solid)
			)
			(layer "F.SilkS")
		)
		(fp_line
			(start -0.094672 0.201008)
			(end -0.094672 -0.198992)
			(stroke
				(width 0.1)
				(type solid)
			)
			(layer "F.SilkS")
		)
		(fp_line
			(start 0.22 0.35)
			(end -0.22 0.35)
			(stroke
				(width 0.15)
				(type solid)
			)
			(layer "F.SilkS")
		)
		(fp_rect
			(start 1.25 0.65)
			(end -1.25 -0.65)
			(stroke
				(width 0.05)
				(type solid)
			)
			(fill no)
			(layer "F.CrtYd")
		)
		(fp_line
			(start 0.201 -0.202)
			(end -0.101 0)
			(stroke
				(width 0.15)
				(type solid)
			)
			(layer "F.Fab")
		)
		(fp_line
			(start -0.199 -0.202)
			(end -0.199 0.1)
			(stroke
				(width 0.15)
				(type solid)
			)
			(layer "F.Fab")
		)
		(fp_line
			(start 0.599 0)
			(end 0.201 0)
			(stroke
				(width 0.15)
				(type solid)
			)
			(layer "F.Fab")
		)
		(fp_line
			(start 0.201 0)
			(end 0.201 -0.202)
			(stroke
				(width 0.15)
				(type solid)
			)
			(layer "F.Fab")
		)
		(fp_line
			(start -0.101 0)
			(end 0.201 0.2)
			(stroke
				(width 0.15)
				(type solid)
			)
			(layer "F.Fab")
		)
		(fp_line
			(start -0.199 0)
			(end -0.597 0)
			(stroke
				(width 0.15)
				(type solid)
			)
			(layer "F.Fab")
		)
		(fp_line
			(start 0.201 0.2)
			(end 0.201 0)
			(stroke
				(width 0.15)
				(type solid)
			)
			(layer "F.Fab")
		)
		(fp_line
			(start -0.199 0.2)
			(end -0.199 0.1)
			(stroke
				(width 0.15)
				(type solid)
			)
			(layer "F.Fab")
		)
		(fp_rect
			(start 0.848 0.4)
			(end -0.85 -0.402)
			(stroke
				(width 0.15)
				(type solid)
			)
			(fill no)
			(layer "F.Fab")
		)
		(fp_text user "${REFERENCE}"
			(at -1.4224 5.999 90)
			(layer "F.Fab")
			(effects
				(font
					(size 0.7 0.7)
					(thickness 0.15)
				)
				(justify left bottom)
			)
		)
		(fp_text user "License: Apache-2.0"
			(at -1.4224 3.599 90)
			(layer "F.Fab")
			(effects
				(font
					(size 0.7 0.7)
					(thickness 0.15)
				)
				(justify left bottom)
			)
		)
		(fp_text user "Author: Antmicro"
			(at -1.4224 4.799 90)
			(layer "F.Fab")
			(effects
				(font
					(size 0.7 0.7)
					(thickness 0.15)
				)
				(justify left bottom)
			)
		)
		(pad "1" smd roundrect
			(at -0.7 0 270)
			(size 0.8 1)
			(layers "F.Cu" "F.Mask" "F.Paste")
			(roundrect_rratio 0.2)
			(net 1 "GND")
			(pinfunction "C")
			(pintype "passive")
		)
		(pad "2" smd roundrect
			(at 0.7 0 270)
			(size 0.8 1)
			(layers "F.Cu" "F.Mask" "F.Paste")
			(roundrect_rratio 0.2)
			(net 533 "Net-(D18-A)")
			(pinfunction "A")
			(pintype "passive")
		)
	)
	(footprint "antmicro-footprints:DHVQFN-14-1EP_2.5x3mm"
		(layer "F.Cu")
		(at 152.48 112.25)
		(property "Reference" "U80"
			(at 1.32 -1.05 0)
			(layer "F.SilkS")
			(effects
				(font
					(size 0.7 0.7)
					(thickness 0.15)
				)
				(justify left bottom)
			)
		)
		(property "Value" "NTS0104_DHVQFN"
			(at 0 2.897999 0)
			(layer "F.Fab")
			(effects
				(font
					(size 0.7 0.7)
					(thickness 0.15)
				)
				(justify left bottom)
			)
		)
		(property "Datasheet" "https://www.nxp.com/docs/en/data-sheet/NTS0104.pdf"
			(at 0 0 0)
			(layer "F.Fab")
			(hide yes)
			(effects
				(font
					(size 1.27 1.27)
					(thickness 0.15)
				)
			)
		)
		(property "Description" "Voltage Level Translator Bidirectional 1 Circuit 4 Channel 50Mbps 14-DHVQFN (2.5x3)"
			(at 0 0 0)
			(layer "F.Fab")
			(hide yes)
			(effects
				(font
					(size 1.27 1.27)
					(thickness 0.15)
				)
			)
		)
		(property "MPN" "NTS0104BQ"
			(at 0 0 0)
			(unlocked yes)
			(layer "F.Fab")
			(hide yes)
			(effects
				(font
					(size 1 1)
					(thickness 0.15)
				)
			)
		)
		(property "Manufacturer" "NXP"
			(at 0 0 0)
			(unlocked yes)
			(layer "F.Fab")
			(hide yes)
			(effects
				(font
					(size 1 1)
					(thickness 0.15)
				)
			)
		)
		(property "Author" "Antmicro"
			(at 0 0 0)
			(unlocked yes)
			(layer "F.Fab")
			(hide yes)
			(effects
				(font
					(size 1 1)
					(thickness 0.15)
				)
			)
		)
		(property "License" "Apache-2.0"
			(at 0 0 0)
			(unlocked yes)
			(layer "F.Fab")
			(hide yes)
			(effects
				(font
					(size 1 1)
					(thickness 0.15)
				)
			)
		)
		(sheetname "/SoM_IO/")
		(sheetfile "som_io.kicad_sch")
		(attr smd)
		(fp_line
			(start -1.351 -1.601)
			(end -0.499999 -1.601)
			(stroke
				(width 0.15)
				(type solid)
			)
			(layer "F.SilkS")
		)
		(fp_line
			(start -1.351 1.6)
			(end -1.351 1.249)
			(stroke
				(width 0.15)
				(type solid)
			)
			(layer "F.SilkS")
		)
		(fp_line
			(start -1.351 1.6)
			(end -0.5 1.6)
			(stroke
				(width 0.15)
				(type solid)
			)
			(layer "F.SilkS")
		)
		(fp_line
			(start -1.35 -1.601)
			(end -1.35 -1.25)
			(stroke
				(width 0.15)
				(type solid)
			)
			(layer "F.SilkS")
		)
		(fp_line
			(start 0.494 1.6)
			(end 1.35 1.6)
			(stroke
				(width 0.15)
				(type solid)
			)
			(layer "F.SilkS")
		)
		(fp_line
			(start 1.35 -1.601)
			(end 0.494 -1.601)
			(stroke
				(width 0.15)
				(type solid)
			)
			(layer "F.SilkS")
		)
		(fp_line
			(start 1.35 -1.601)
			(end 1.35 -1.25)
			(stroke
				(width 0.15)
				(type solid)
			)
			(layer "F.SilkS")
		)
		(fp_line
			(start 1.35 1.6)
			(end 1.35 1.249)
			(stroke
				(width 0.15)
				(type solid)
			)
			(layer "F.SilkS")
		)
		(fp_circle
			(center -0.7 -1.85)
			(end -0.653 -1.85)
			(stroke
				(width 0.15)
				(type solid)
			)
			(fill yes)
			(layer "F.SilkS")
		)
		(fp_poly
			(pts
				(xy -1.85 -2) (xy 1.8 -2) (xy 1.8 1.95) (xy -1.85 1.95)
			)
			(stroke
				(width 0.05)
				(type solid)
			)
			(fill no)
			(layer "F.CrtYd")
		)
		(fp_line
			(start -1.25 -1.25)
			(end -1 -1.5)
			(stroke
				(width 0.15)
				(type solid)
			)
			(layer "F.Fab")
		)
		(fp_line
			(start -1.25 1.499001)
			(end -1.25 -1.25)
			(stroke
				(width 0.15)
				(type solid)
			)
			(layer "F.Fab")
		)
		(fp_line
			(start -1 -1.5)
			(end 1.249 -1.5)
			(stroke
				(width 0.15)
				(type solid)
			)
			(layer "F.Fab")
		)
		(fp_line
			(start 1.248999 1.499)
			(end -1.25 1.499001)
			(stroke
				(width 0.15)
				(type solid)
			)
			(layer "F.Fab")
		)
		(fp_line
			(start 1.249 -1.5)
			(end 1.248999 1.499)
			(stroke
				(width 0.15)
				(type solid)
			)
			(layer "F.Fab")
		)
		(fp_text user "Author: Antmicro"
			(at -1.841001 7.296 0)
			(layer "F.Fab")
			(effects
				(font
					(size 0.7 0.7)
					(thickness 0.15)
				)
				(justify left bottom)
			)
		)
		(fp_text user "${REFERENCE}"
			(at -1.841 4.896999 0)
			(layer "F.Fab")
			(effects
				(font
					(size 0.7 0.7)
					(thickness 0.15)
				)
				(justify left bottom)
			)
		)
		(fp_text user "License: Apache-2.0"
			(at -1.841001 6.097 0)
			(layer "F.Fab")
			(effects
				(font
					(size 0.7 0.7)
					(thickness 0.15)
				)
				(justify left bottom)
			)
		)
		(pad "1" smd oval
			(at -0.25 -1.5)
			(size 0.3 0.8)
			(layers "F.Cu" "F.Mask" "F.Paste")
			(net 11 "+1V8")
			(pinfunction "VCC_A")
			(pintype "power_in")
		)
		(pad "2" smd oval
			(at -1.25 -1 90)
			(size 0.3 0.8)
			(layers "F.Cu" "F.Mask" "F.Paste")
			(net 139 "/SoM_IO/I2C2_SCL_1V8")
			(pinfunction "A1")
			(pintype "passive")
		)
		(pad "3" smd oval
			(at -1.25 -0.5 90)
			(size 0.3 0.8)
			(layers "F.Cu" "F.Mask" "F.Paste")
			(net 167 "/SoM_IO/I2C2_SDA_1V8")
			(pinfunction "A2")
			(pintype "passive")
		)
		(pad "4" smd oval
			(at -1.249999 0 90)
			(size 0.3 0.8)
			(layers "F.Cu" "F.Mask" "F.Paste")
			(net 133 "/SoM_IO/I2C5_SCL_1V8")
			(pinfunction "A3")
			(pintype "passive")
		)
		(pad "5" smd oval
			(at -1.25 0.494 90)
			(size 0.3 0.8)
			(layers "F.Cu" "F.Mask" "F.Paste")
			(net 112 "/SoM_IO/I2C5_SDA_1V8")
			(pinfunction "A4")
			(pintype "passive")
		)
		(pad "6" smd oval
			(at -1.25 0.994001 90)
			(size 0.3 0.8)
			(layers "F.Cu" "F.Mask" "F.Paste")
			(net 1329 "unconnected-(U80-NC-Pad6)")
			(pinfunction "NC")
			(pintype "no_connect")
		)
		(pad "7" smd oval
			(at -0.25 1.499)
			(size 0.3 0.8)
			(layers "F.Cu" "F.Mask" "F.Paste")
			(net 1 "GND")
			(pinfunction "GND")
			(pintype "power_in")
		)
		(pad "8" smd oval
			(at 0.244 1.499)
			(size 0.3 0.8)
			(layers "F.Cu" "F.Mask" "F.Paste")
			(net 11 "+1V8")
			(pinfunction "OE")
			(pintype "passive")
		)
		(pad "9" smd oval
			(at 1.249 0.994001 90)
			(size 0.3 0.8)
			(layers "F.Cu" "F.Mask" "F.Paste")
			(net 1328 "unconnected-(U80-NC-Pad9)")
			(pinfunction "NC")
			(pintype "no_connect")
		)
		(pad "10" smd oval
			(at 1.249 0.494 90)
			(size 0.3 0.8)
			(layers "F.Cu" "F.Mask" "F.Paste")
			(net 43 "/Peripherals/I2C_{CONN}.SDA")
			(pinfunction "B4")
			(pintype "passive")
		)
		(pad "11" smd oval
			(at 1.248999 0 90)
			(size 0.3 0.8)
			(layers "F.Cu" "F.Mask" "F.Paste")
			(net 42 "/Peripherals/I2C_{CONN}.SCL")
			(pinfunction "B3")
			(pintype "passive")
		)
		(pad "12" smd oval
			(at 1.249 -0.5 90)
			(size 0.3 0.8)
			(layers "F.Cu" "F.Mask" "F.Paste")
			(net 850 "/I2C_{SYS}.SDA")
			(pinfunction "B2")
			(pintype "passive")
		)
		(pad "13" smd oval
			(at 1.249 -1 90)
			(size 0.3 0.8)
			(layers "F.Cu" "F.Mask" "F.Paste")
			(net 853 "/I2C_{SYS}.SCL")
			(pinfunction "B1")
			(pintype "passive")
		)
		(pad "14" smd oval
			(at 0.244 -1.5)
			(size 0.3 0.8)
			(layers "F.Cu" "F.Mask" "F.Paste")
			(net 2 "+3V3")
			(pinfunction "VCC_B")
			(pintype "power_in")
		)
		(pad "15" smd rect
			(at 0 0)
			(size 1 1.5)
			(layers "F.Cu" "F.Mask" "F.Paste")
			(net 1 "GND")
			(pinfunction "GNDPAD")
			(pintype "power_in")
		)
	)
	(footprint "antmicro-footprints:R_0402_1005Metric"
		(layer "F.Cu")
		(at 180.8 107.15 -90)
		(descr "Resistor SMD 0402")
		(tags "resistor SMD 0402")
		(property "Reference" "R37"
			(at -3.15 0.4 90)
			(layer "F.SilkS")
			(effects
				(font
					(size 0.7 0.7)
					(thickness 0.15)
				)
				(justify right top)
			)
		)
		(property "Value" "R_499k_0402"
			(at -1.011843 1.772047 90)
			(layer "F.Fab")
			(effects
				(font
					(size 0.7 0.7)
					(thickness 0.15)
				)
				(justify right top)
			)
		)
		(property "Datasheet" "https://www.mouser.com/datasheet/2/54/cr-1858361.pdf"
			(at 0 0 90)
			(layer "F.Fab")
			(hide yes)
			(effects
				(font
					(size 1.27 1.27)
					(thickness 0.15)
				)
			)
		)
		(property "Description" "SMD Chip Resistor, 499 kohm, ± 1%, 63 mW, 0402 [1005 Metric], Thick Film, General Purpose"
			(at 0 0 90)
			(layer "F.Fab")
			(hide yes)
			(effects
				(font
					(size 1.27 1.27)
					(thickness 0.15)
				)
			)
		)
		(property "MPN" "CR0402-FX-4993GLF"
			(at 0 0 270)
			(unlocked yes)
			(layer "F.Fab")
			(hide yes)
			(effects
				(font
					(size 1 1)
					(thickness 0.15)
				)
			)
		)
		(property "Manufacturer" "Bourns"
			(at 0 0 270)
			(unlocked yes)
			(layer "F.Fab")
			(hide yes)
			(effects
				(font
					(size 1 1)
					(thickness 0.15)
				)
			)
		)
		(property "License" "Apache-2.0"
			(at 0 0 270)
			(unlocked yes)
			(layer "F.Fab")
			(hide yes)
			(effects
				(font
					(size 1 1)
					(thickness 0.15)
				)
			)
		)
		(property "Author" "Antmicro"
			(at 0 0 270)
			(unlocked yes)
			(layer "F.Fab")
			(hide yes)
			(effects
				(font
					(size 1 1)
					(thickness 0.15)
				)
			)
		)
		(property "Val" "499k"
			(at 0 0 270)
			(unlocked yes)
			(layer "F.Fab")
			(hide yes)
			(effects
				(font
					(size 1 1)
					(thickness 0.15)
				)
			)
		)
		(property "Tolerance" "1%"
			(at 0 0 270)
			(unlocked yes)
			(layer "F.Fab")
			(hide yes)
			(effects
				(font
					(size 1 1)
					(thickness 0.15)
				)
			)
		)
		(sheetname "/DCDC/")
		(sheetfile "dcdc.kicad_sch")
		(attr smd)
		(fp_rect
			(start -0.925 -0.47)
			(end 0.925 0.47)
			(stroke
				(width 0.05)
				(type default)
			)
			(fill no)
			(layer "F.CrtYd")
		)
		(fp_rect
			(start -0.5 -0.25)
			(end 0.5 0.25)
			(stroke
				(width 0.15)
				(type solid)
			)
			(fill no)
			(layer "F.Fab")
		)
		(fp_text user "License: Apache-2.0"
			(at -0.95 5.169 90)
			(layer "F.Fab")
			(effects
				(font
					(size 0.7 0.7)
					(thickness 0.15)
				)
				(justify right top)
			)
		)
		(fp_text user "${REFERENCE}"
			(at -0.95 3.168 90)
			(layer "F.Fab")
			(effects
				(font
					(size 0.7 0.7)
					(thickness 0.15)
				)
				(justify right top)
			)
		)
		(fp_text user "Author: Antmicro"
			(at -0.95 4.169 90)
			(layer "F.Fab")
			(effects
				(font
					(size 0.7 0.7)
					(thickness 0.15)
				)
				(justify right top)
			)
		)
		(pad "1" smd roundrect
			(at -0.48 0 270)
			(size 0.59 0.64)
			(layers "F.Cu" "F.Mask" "F.Paste")
			(roundrect_rratio 0.25)
			(net 1 "GND")
			(pintype "passive")
		)
		(pad "2" smd roundrect
			(at 0.48 0 270)
			(size 0.59 0.64)
			(layers "F.Cu" "F.Mask" "F.Paste")
			(roundrect_rratio 0.25)
			(net 1212 "/DCDC/5V_MODE1")
			(pintype "passive")
		)
	)
)
